(kicad_pcb
	(version 20260206)
	(generator "pcbnew")
	(generator_version "10.0")
	(general
		(thickness 1.6)
		(legacy_teardrops no)
	)
	(paper "A4")
	(title_block
		(title "03242023_DA0F0TMBIJ0_F0T_Motherboard_J_brd_V01_OCP.brd")
		(comment 1 "Grand Teton / footprints 2404-2410 of 6105")
	)
	(layers
		(0 "F.Cu" signal "TOP")
		(4 "In1.Cu" signal "GND")
		(6 "In2.Cu" signal "IN1")
		(8 "In3.Cu" signal "GND1")
		(10 "In4.Cu" signal "IN2")
		(12 "In5.Cu" signal "GND2")
		(14 "In6.Cu" signal "IN3")
		(16 "In7.Cu" signal "GND3")
		(18 "In8.Cu" signal "VCC")
		(20 "In9.Cu" signal "VCC1")
		(22 "In10.Cu" signal "GND4")
		(24 "In11.Cu" signal "IN4")
		(26 "In12.Cu" signal "GND5")
		(28 "In13.Cu" signal "IN5")
		(30 "In14.Cu" signal "GND6")
		(32 "In15.Cu" signal "IN6")
		(34 "In16.Cu" signal "GND7")
		(2 "B.Cu" signal "BOTTOM")
		(9 "F.Adhes" user "F.Adhesive")
		(11 "B.Adhes" user "B.Adhesive")
		(13 "F.Paste" user "Package Geometry/Pastemask Top")
		(15 "B.Paste" user "Package Geometry/Pastemask Bottom")
		(5 "F.SilkS" user "Ref Des/Silkscreen Top")
		(7 "B.SilkS" user "Ref Des/Silkscreen Bottom")
		(1 "F.Mask" user "Board Geometry/Soldermask Top")
		(3 "B.Mask" user "Board Geometry/Soldermask Bottom")
		(17 "Dwgs.User" user "User.Drawings")
		(19 "Cmts.User" user "User.Comments")
		(21 "Eco1.User" user "User.Eco1")
		(23 "Eco2.User" user "User.Eco2")
		(25 "Edge.Cuts" user "Board Geometry/Outline")
		(27 "Margin" user)
		(31 "F.CrtYd" user "Package Geometry/Place Bound Top")
		(29 "B.CrtYd" user "Package Geometry/Place Bound Bottom")
		(35 "F.Fab" user "Ref Des/Assembly Top")
		(33 "B.Fab" user "Ref Des/Assembly Bottom")
	)
	(footprint ""
		(layer "F.Cu")
		(at 24.93137 -42.992802 180)
		(property "Reference" "R3065"
			(at 0 0 180)
			(layer "F.SilkS")
			(hide yes)
			(effects
				(font
					(size 1.27 1.27)
				)
			)
		)
		(property "Value" ""
			(at 0 0 180)
			(layer "F.Fab")
			(effects
				(font
					(size 1.27 1.27)
				)
			)
		)
		(duplicate_pad_numbers_are_jumpers no)
		(fp_line
			(start 0.7874 0.4064)
			(end -0.7874 0.4064)
			(stroke
				(width 0.1524)
				(type default)
			)
			(layer "F.SilkS")
		)
		(fp_line
			(start 0.7874 -0.4064)
			(end 0.7874 0.4064)
			(stroke
				(width 0.1524)
				(type default)
			)
			(layer "F.SilkS")
		)
		(fp_line
			(start -0.7874 0.4064)
			(end -0.7874 -0.4064)
			(stroke
				(width 0.1524)
				(type default)
			)
			(layer "F.SilkS")
		)
		(fp_line
			(start -0.7874 -0.4064)
			(end 0.7874 -0.4064)
			(stroke
				(width 0.1524)
				(type default)
			)
			(layer "F.SilkS")
		)
		(fp_line
			(start 0.67945 0.3048)
			(end 0.120396 0.3048)
			(stroke
				(width 0.1)
				(type default)
			)
			(layer "F.Fab")
		)
		(fp_line
			(start 0.67945 -0.3048)
			(end 0.67945 0.3048)
			(stroke
				(width 0.1)
				(type default)
			)
			(layer "F.Fab")
		)
		(fp_line
			(start 0.12065 -0.2794)
			(end 0.12065 -0.3048)
			(stroke
				(width 0.1)
				(type default)
			)
			(layer "F.Fab")
		)
		(fp_line
			(start 0.12065 -0.3048)
			(end 0.67945 -0.3048)
			(stroke
				(width 0.1)
				(type default)
			)
			(layer "F.Fab")
		)
		(fp_line
			(start 0.120396 0.3048)
			(end 0.120396 0.2794)
			(stroke
				(width 0.1)
				(type default)
			)
			(layer "F.Fab")
		)
		(fp_line
			(start 0.120396 0.2794)
			(end -0.12065 0.2794)
			(stroke
				(width 0.1)
				(type default)
			)
			(layer "F.Fab")
		)
		(fp_line
			(start -0.12065 0.3048)
			(end -0.67945 0.3048)
			(stroke
				(width 0.1)
				(type default)
			)
			(layer "F.Fab")
		)
		(fp_line
			(start -0.12065 0.2794)
			(end -0.12065 0.3048)
			(stroke
				(width 0.1)
				(type default)
			)
			(layer "F.Fab")
		)
		(fp_line
			(start -0.12065 -0.2794)
			(end 0.12065 -0.2794)
			(stroke
				(width 0.1)
				(type default)
			)
			(layer "F.Fab")
		)
		(fp_line
			(start -0.12065 -0.305054)
			(end -0.12065 -0.2794)
			(stroke
				(width 0.1)
				(type default)
			)
			(layer "F.Fab")
		)
		(fp_line
			(start -0.67945 0.3048)
			(end -0.67945 -0.305054)
			(stroke
				(width 0.1)
				(type default)
			)
			(layer "F.Fab")
		)
		(fp_line
			(start -0.67945 -0.305054)
			(end -0.12065 -0.305054)
			(stroke
				(width 0.1)
				(type default)
			)
			(layer "F.Fab")
		)
		(pad "1" smd circle
			(at -0.40005 0 180)
			(size 0 0)
			(layers "F.Cu" "F.Mask" "F.Paste")
			(net "FM_BIOS_POST_CMPLT_N")
		)
		(pad "2" smd circle
			(at 0.40005 0 180)
			(size 0 0)
			(layers "F.Cu" "F.Mask" "F.Paste")
			(net "FM_BIOS_POST_CMPLT_HDR_N")
		)
	)
	(footprint ""
		(layer "F.Cu")
		(at 242.291616 -398.78 90)
		(property "Reference" "PPQ1"
			(at -8.230108 -1.771396 0)
			(unlocked yes)
			(layer "F.SilkS")
			(effects
				(font
					(size 0.7874 0.5842)
					(thickness 0.1524)
				)
				(justify left)
			)
		)
		(property "Value" ""
			(at 0 0 90)
			(layer "F.Fab")
			(effects
				(font
					(size 1.27 1.27)
				)
			)
		)
		(duplicate_pad_numbers_are_jumpers no)
		(fp_line
			(start 2.350008 -2.649982)
			(end 2.350008 -2.4892)
			(stroke
				(width 0.1524)
				(type default)
			)
			(layer "F.SilkS")
		)
		(fp_line
			(start -2.350008 -2.649982)
			(end 2.350008 -2.649982)
			(stroke
				(width 0.1524)
				(type default)
			)
			(layer "F.SilkS")
		)
		(fp_line
			(start -2.350008 -2.4384)
			(end -2.350008 -2.649982)
			(stroke
				(width 0.1524)
				(type default)
			)
			(layer "F.SilkS")
		)
		(fp_line
			(start 2.350008 2.4892)
			(end 2.350008 2.649982)
			(stroke
				(width 0.1524)
				(type default)
			)
			(layer "F.SilkS")
		)
		(fp_line
			(start 2.350008 2.649982)
			(end -2.350008 2.649982)
			(stroke
				(width 0.1524)
				(type default)
			)
			(layer "F.SilkS")
		)
		(fp_line
			(start -2.350008 2.649982)
			(end -2.350008 2.413)
			(stroke
				(width 0.1524)
				(type default)
			)
			(layer "F.SilkS")
		)
		(fp_poly
			(pts
				(xy -3.717544 -1.905) (xy -4.758944 -2.3241) (xy -4.758944 -1.524)
			)
			(stroke
				(width 0)
				(type default)
			)
			(fill yes)
			(layer "F.SilkS")
		)
		(fp_line
			(start 2.350008 -2.649982)
			(end 2.350008 2.649982)
			(stroke
				(width 0.1)
				(type default)
			)
			(layer "F.Fab")
		)
		(fp_line
			(start -2.350008 -2.649982)
			(end 2.350008 -2.649982)
			(stroke
				(width 0.1)
				(type default)
			)
			(layer "F.Fab")
		)
		(fp_line
			(start 2.350008 2.649982)
			(end -2.350008 2.649982)
			(stroke
				(width 0.1)
				(type default)
			)
			(layer "F.Fab")
		)
		(fp_line
			(start -2.350008 2.649982)
			(end -2.350008 -2.649982)
			(stroke
				(width 0.1)
				(type default)
			)
			(layer "F.Fab")
		)
		(fp_poly
			(pts
				(xy -3.717544 -1.905) (xy -4.758944 -2.3241) (xy -4.758944 -1.524)
			)
			(stroke
				(width 0)
				(type default)
			)
			(fill yes)
			(layer "F.Fab")
		)
		(pad "1" smd rect
			(at -2.999994 -1.905)
			(size 0.7112 1.1684)
			(layers "F.Cu" "F.Mask" "F.Paste")
			(net "P12V_AUX")
		)
		(pad "2" smd rect
			(at -2.999994 -0.635)
			(size 0.7112 1.1684)
			(layers "F.Cu" "F.Mask" "F.Paste")
			(net "P12V_AUX")
		)
		(pad "3" smd rect
			(at -2.999994 0.635)
			(size 0.7112 1.1684)
			(layers "F.Cu" "F.Mask" "F.Paste")
			(net "P12V_AUX")
		)
		(pad "4" smd rect
			(at -2.999994 1.905)
			(size 0.7112 1.1684)
			(layers "F.Cu" "F.Mask" "F.Paste")
			(net "P12V_HSC_GATE_G5")
		)
		(pad "5" smd circle
			(at 0.925068 0)
			(size 0 0)
			(layers "F.Cu" "F.Mask" "F.Paste")
			(net "P12V_MAIN_R")
		)
		(zone
			(layer "F.Cu")
			(hatch none 0.5)
			(connect_pads
				(clearance 0)
			)
			(min_thickness 0.25)
			(keepout
				(tracks not_allowed)
				(vias allowed)
				(pads allowed)
				(copperpour not_allowed)
				(footprints allowed)
			)
			(placement
				(enabled no)
				(sheetname "")
			)
			(fill
				(thermal_gap 0.5)
				(thermal_bridge_width 0.5)
				(island_removal_mode 0)
			)
			(polygon
				(pts
					(xy 240.132616 -397.3322) (xy 244.450616 -397.3322) (xy 244.933216 -397.3322) (xy 244.933216 -396.4305)
					(xy 239.650016 -396.4305) (xy 239.650016 -397.3322)
				)
			)
		)
	)
	(footprint ""
		(layer "F.Cu")
		(at 421.780208 -141.756638 180)
		(property "Reference" "PJ46"
			(at 2.878328 1.442212 0)
			(unlocked yes)
			(layer "F.SilkS")
			(effects
				(font
					(size 0.7874 0.5842)
					(thickness 0.1524)
				)
				(justify left)
			)
		)
		(property "Value" ""
			(at 0 0 180)
			(layer "F.Fab")
			(effects
				(font
					(size 1.27 1.27)
				)
			)
		)
		(duplicate_pad_numbers_are_jumpers no)
		(pad "1" smd circle
			(at -0.7493 0 270)
			(size 0 0)
			(layers "F.Cu" "F.Mask" "F.Paste")
			(net "VSENSE_PVCCFA_EHV_CPU0_DP")
		)
		(pad "2" smd rect
			(at 0.7493 0 90)
			(size 0.7112 0.8128)
			(layers "F.Cu" "F.Mask" "F.Paste")
			(net "SH_PVCCFA_EHV_CPU0")
		)
		(zone
			(layer "F.Cu")
			(hatch none 0.5)
			(connect_pads
				(clearance 0)
			)
			(min_thickness 0.25)
			(keepout
				(tracks allowed)
				(vias not_allowed)
				(pads allowed)
				(copperpour not_allowed)
				(footprints allowed)
			)
			(placement
				(enabled no)
				(sheetname "")
			)
			(fill
				(thermal_gap 0.5)
				(thermal_bridge_width 0.5)
				(island_removal_mode 0)
			)
			(polygon
				(pts
					(xy 420.573708 -141.350238) (xy 422.961308 -141.350238) (xy 422.961308 -142.167864) (xy 420.573708 -142.167864)
				)
			)
		)
	)
	(footprint ""
		(layer "F.Cu")
		(at 359.7656 -404.7998 180)
		(property "Reference" "R4732"
			(at 0 0 180)
			(layer "F.SilkS")
			(hide yes)
			(effects
				(font
					(size 1.27 1.27)
				)
			)
		)
		(property "Value" ""
			(at 0 0 180)
			(layer "F.Fab")
			(effects
				(font
					(size 1.27 1.27)
				)
			)
		)
		(duplicate_pad_numbers_are_jumpers no)
		(fp_line
			(start 0.7874 0.4064)
			(end -0.7874 0.4064)
			(stroke
				(width 0.1524)
				(type default)
			)
			(layer "F.SilkS")
		)
		(fp_line
			(start 0.7874 -0.4064)
			(end 0.7874 0.4064)
			(stroke
				(width 0.1524)
				(type default)
			)
			(layer "F.SilkS")
		)
		(fp_line
			(start -0.7874 0.4064)
			(end -0.7874 -0.4064)
			(stroke
				(width 0.1524)
				(type default)
			)
			(layer "F.SilkS")
		)
		(fp_line
			(start -0.7874 -0.4064)
			(end 0.7874 -0.4064)
			(stroke
				(width 0.1524)
				(type default)
			)
			(layer "F.SilkS")
		)
		(fp_line
			(start 0.67945 0.3048)
			(end 0.120396 0.3048)
			(stroke
				(width 0.1)
				(type default)
			)
			(layer "F.Fab")
		)
		(fp_line
			(start 0.67945 -0.3048)
			(end 0.67945 0.3048)
			(stroke
				(width 0.1)
				(type default)
			)
			(layer "F.Fab")
		)
		(fp_line
			(start 0.12065 -0.2794)
			(end 0.12065 -0.3048)
			(stroke
				(width 0.1)
				(type default)
			)
			(layer "F.Fab")
		)
		(fp_line
			(start 0.12065 -0.3048)
			(end 0.67945 -0.3048)
			(stroke
				(width 0.1)
				(type default)
			)
			(layer "F.Fab")
		)
		(fp_line
			(start 0.120396 0.3048)
			(end 0.120396 0.2794)
			(stroke
				(width 0.1)
				(type default)
			)
			(layer "F.Fab")
		)
		(fp_line
			(start 0.120396 0.2794)
			(end -0.12065 0.2794)
			(stroke
				(width 0.1)
				(type default)
			)
			(layer "F.Fab")
		)
		(fp_line
			(start -0.12065 0.3048)
			(end -0.67945 0.3048)
			(stroke
				(width 0.1)
				(type default)
			)
			(layer "F.Fab")
		)
		(fp_line
			(start -0.12065 0.2794)
			(end -0.12065 0.3048)
			(stroke
				(width 0.1)
				(type default)
			)
			(layer "F.Fab")
		)
		(fp_line
			(start -0.12065 -0.2794)
			(end 0.12065 -0.2794)
			(stroke
				(width 0.1)
				(type default)
			)
			(layer "F.Fab")
		)
		(fp_line
			(start -0.12065 -0.305054)
			(end -0.12065 -0.2794)
			(stroke
				(width 0.1)
				(type default)
			)
			(layer "F.Fab")
		)
		(fp_line
			(start -0.67945 0.3048)
			(end -0.67945 -0.305054)
			(stroke
				(width 0.1)
				(type default)
			)
			(layer "F.Fab")
		)
		(fp_line
			(start -0.67945 -0.305054)
			(end -0.12065 -0.305054)
			(stroke
				(width 0.1)
				(type default)
			)
			(layer "F.Fab")
		)
		(pad "1" smd circle
			(at -0.40005 0 180)
			(size 0 0)
			(layers "F.Cu" "F.Mask" "F.Paste")
			(net "P3V3_AUX")
		)
		(pad "2" smd circle
			(at 0.40005 0 180)
			(size 0 0)
			(layers "F.Cu" "F.Mask" "F.Paste")
			(net "PRSNT_CABLE_SWB_B2")
		)
	)
	(footprint ""
		(layer "F.Cu")
		(at 160.83788 -112.232948)
		(property "Reference" "R3476"
			(at 0 0 0)
			(layer "F.SilkS")
			(hide yes)
			(effects
				(font
					(size 1.27 1.27)
				)
			)
		)
		(property "Value" ""
			(at 0 0 0)
			(layer "F.Fab")
			(effects
				(font
					(size 1.27 1.27)
				)
			)
		)
		(duplicate_pad_numbers_are_jumpers no)
		(fp_line
			(start -0.7874 -0.4064)
			(end 0.7874 -0.4064)
			(stroke
				(width 0.1524)
				(type default)
			)
			(layer "F.SilkS")
		)
		(fp_line
			(start -0.7874 0.4064)
			(end -0.7874 -0.4064)
			(stroke
				(width 0.1524)
				(type default)
			)
			(layer "F.SilkS")
		)
		(fp_line
			(start 0.7874 -0.4064)
			(end 0.7874 0.4064)
			(stroke
				(width 0.1524)
				(type default)
			)
			(layer "F.SilkS")
		)
		(fp_line
			(start 0.7874 0.4064)
			(end -0.7874 0.4064)
			(stroke
				(width 0.1524)
				(type default)
			)
			(layer "F.SilkS")
		)
		(fp_line
			(start -0.67945 -0.305054)
			(end -0.12065 -0.305054)
			(stroke
				(width 0.1)
				(type default)
			)
			(layer "F.Fab")
		)
		(fp_line
			(start -0.67945 0.3048)
			(end -0.67945 -0.305054)
			(stroke
				(width 0.1)
				(type default)
			)
			(layer "F.Fab")
		)
		(fp_line
			(start -0.12065 -0.305054)
			(end -0.12065 -0.2794)
			(stroke
				(width 0.1)
				(type default)
			)
			(layer "F.Fab")
		)
		(fp_line
			(start -0.12065 -0.2794)
			(end 0.12065 -0.2794)
			(stroke
				(width 0.1)
				(type default)
			)
			(layer "F.Fab")
		)
		(fp_line
			(start -0.12065 0.2794)
			(end -0.12065 0.3048)
			(stroke
				(width 0.1)
				(type default)
			)
			(layer "F.Fab")
		)
		(fp_line
			(start -0.12065 0.3048)
			(end -0.67945 0.3048)
			(stroke
				(width 0.1)
				(type default)
			)
			(layer "F.Fab")
		)
		(fp_line
			(start 0.120396 0.2794)
			(end -0.12065 0.2794)
			(stroke
				(width 0.1)
				(type default)
			)
			(layer "F.Fab")
		)
		(fp_line
			(start 0.120396 0.3048)
			(end 0.120396 0.2794)
			(stroke
				(width 0.1)
				(type default)
			)
			(layer "F.Fab")
		)
		(fp_line
			(start 0.12065 -0.3048)
			(end 0.67945 -0.3048)
			(stroke
				(width 0.1)
				(type default)
			)
			(layer "F.Fab")
		)
		(fp_line
			(start 0.12065 -0.2794)
			(end 0.12065 -0.3048)
			(stroke
				(width 0.1)
				(type default)
			)
			(layer "F.Fab")
		)
		(fp_line
			(start 0.67945 -0.3048)
			(end 0.67945 0.3048)
			(stroke
				(width 0.1)
				(type default)
			)
			(layer "F.Fab")
		)
		(fp_line
			(start 0.67945 0.3048)
			(end 0.120396 0.3048)
			(stroke
				(width 0.1)
				(type default)
			)
			(layer "F.Fab")
		)
		(pad "1" smd circle
			(at -0.40005 0)
			(size 0 0)
			(layers "F.Cu" "F.Mask" "F.Paste")
			(net "GPU_FPGA_THERM_OVERT_ISO_N")
		)
		(pad "2" smd circle
			(at 0.40005 0)
			(size 0 0)
			(layers "F.Cu" "F.Mask" "F.Paste")
			(net "GPU_FPGA_THERM_OVERT_ISO_R_N")
		)
	)
	(footprint ""
		(layer "F.Cu")
		(at 339.910928 -408.517344 -90)
		(property "Reference" "C925"
			(at 0 0 270)
			(layer "F.SilkS")
			(hide yes)
			(effects
				(font
					(size 1.27 1.27)
				)
			)
		)
		(property "Value" ""
			(at 0 0 270)
			(layer "F.Fab")
			(effects
				(font
					(size 1.27 1.27)
				)
			)
		)
		(duplicate_pad_numbers_are_jumpers no)
		(fp_line
			(start -0.299974 0.150114)
			(end -0.299974 -0.150114)
			(stroke
				(width 0.1)
				(type default)
			)
			(layer "F.Fab")
		)
		(fp_line
			(start 0.299974 0.150114)
			(end -0.299974 0.150114)
			(stroke
				(width 0.1)
				(type default)
			)
			(layer "F.Fab")
		)
		(fp_line
			(start -0.299974 -0.150114)
			(end 0.299974 -0.150114)
			(stroke
				(width 0.1)
				(type default)
			)
			(layer "F.Fab")
		)
		(fp_line
			(start 0.299974 -0.150114)
			(end 0.299974 0.150114)
			(stroke
				(width 0.1)
				(type default)
			)
			(layer "F.Fab")
		)
		(pad "1" smd rect
			(at -0.2667 0 270)
			(size 0.3048 0.381)
			(layers "F.Cu" "F.Mask" "F.Paste")
			(net "P5E_CPU0_PE0_TX_C_DP<4>")
		)
		(pad "2" smd rect
			(at 0.2667 0 270)
			(size 0.3048 0.381)
			(layers "F.Cu" "F.Mask" "F.Paste")
			(net "P5E_CPU0_PE0_TX_DP<4>")
		)
	)
	(footprint ""
		(layer "F.Cu")
		(at 130.48488 -100.167948 90)
		(property "Reference" "R4411"
			(at 0 0 90)
			(layer "F.SilkS")
			(hide yes)
			(effects
				(font
					(size 1.27 1.27)
				)
			)
		)
		(property "Value" ""
			(at 0 0 90)
			(layer "F.Fab")
			(effects
				(font
					(size 1.27 1.27)
				)
			)
		)
		(duplicate_pad_numbers_are_jumpers no)
		(fp_line
			(start 0.7874 -0.4064)
			(end 0.7874 0.4064)
			(stroke
				(width 0.1524)
				(type default)
			)
			(layer "F.SilkS")
		)
		(fp_line
			(start -0.7874 -0.4064)
			(end 0.7874 -0.4064)
			(stroke
				(width 0.1524)
				(type default)
			)
			(layer "F.SilkS")
		)
		(fp_line
			(start 0.7874 0.4064)
			(end -0.7874 0.4064)
			(stroke
				(width 0.1524)
				(type default)
			)
			(layer "F.SilkS")
		)
		(fp_line
			(start -0.7874 0.4064)
			(end -0.7874 -0.4064)
			(stroke
				(width 0.1524)
				(type default)
			)
			(layer "F.SilkS")
		)
		(fp_line
			(start -0.12065 -0.305054)
			(end -0.12065 -0.2794)
			(stroke
				(width 0.1)
				(type default)
			)
			(layer "F.Fab")
		)
		(fp_line
			(start -0.67945 -0.305054)
			(end -0.12065 -0.305054)
			(stroke
				(width 0.1)
				(type default)
			)
			(layer "F.Fab")
		)
		(fp_line
			(start 0.67945 -0.3048)
			(end 0.67945 0.3048)
			(stroke
				(width 0.1)
				(type default)
			)
			(layer "F.Fab")
		)
		(fp_line
			(start 0.12065 -0.3048)
			(end 0.67945 -0.3048)
			(stroke
				(width 0.1)
				(type default)
			)
			(layer "F.Fab")
		)
		(fp_line
			(start 0.12065 -0.2794)
			(end 0.12065 -0.3048)
			(stroke
				(width 0.1)
				(type default)
			)
			(layer "F.Fab")
		)
		(fp_line
			(start -0.12065 -0.2794)
			(end 0.12065 -0.2794)
			(stroke
				(width 0.1)
				(type default)
			)
			(layer "F.Fab")
		)
		(fp_line
			(start 0.120396 0.2794)
			(end -0.12065 0.2794)
			(stroke
				(width 0.1)
				(type default)
			)
			(layer "F.Fab")
		)
		(fp_line
			(start -0.12065 0.2794)
			(end -0.12065 0.3048)
			(stroke
				(width 0.1)
				(type default)
			)
			(layer "F.Fab")
		)
		(fp_line
			(start 0.67945 0.3048)
			(end 0.120396 0.3048)
			(stroke
				(width 0.1)
				(type default)
			)
			(layer "F.Fab")
		)
		(fp_line
			(start 0.120396 0.3048)
			(end 0.120396 0.2794)
			(stroke
				(width 0.1)
				(type default)
			)
			(layer "F.Fab")
		)
		(fp_line
			(start -0.12065 0.3048)
			(end -0.67945 0.3048)
			(stroke
				(width 0.1)
				(type default)
			)
			(layer "F.Fab")
		)
		(fp_line
			(start -0.67945 0.3048)
			(end -0.67945 -0.305054)
			(stroke
				(width 0.1)
				(type default)
			)
			(layer "F.Fab")
		)
		(pad "1" smd circle
			(at -0.40005 0 90)
			(size 0 0)
			(layers "F.Cu" "F.Mask" "F.Paste")
			(net "P3V3")
		)
		(pad "2" smd circle
			(at 0.40005 0 90)
			(size 0 0)
			(layers "F.Cu" "F.Mask" "F.Paste")
			(net "H_CPU0_MEMTRIP_VT_N")
		)
	)
)
